G04*
G04 #@! TF.GenerationSoftware,Altium Limited,Altium Designer,23.6.0 (18)*
G04*
G04 Layer_Physical_Order=3*
G04 Layer_Color=16440176*
%FSLAX44Y44*%
%MOMM*%
G71*
G04*
G04 #@! TF.SameCoordinates,59133E90-4310-4D8A-9E2C-91A8D2F69FBB*
G04*
G04*
G04 #@! TF.FilePolarity,Positive*
G04*
G01*
G75*
%ADD58C,0.4064*%
%ADD59C,5.5000*%
G36*
X215922Y271812D02*
X64375D01*
Y401814D01*
X65645Y402067D01*
X65914Y401416D01*
X66843Y400487D01*
X68057Y399985D01*
X69370D01*
X70584Y400487D01*
X71513Y401416D01*
X72015Y402630D01*
Y403943D01*
X71513Y405157D01*
X70584Y406086D01*
X69370Y406589D01*
X68057D01*
X66843Y406086D01*
X65914Y405157D01*
X65645Y404507D01*
X64375Y404759D01*
Y415922D01*
X215922D01*
X215922Y271812D01*
D02*
G37*
G36*
X63000Y413000D02*
Y270438D01*
X215922D01*
X215922Y35578D01*
X214250D01*
X214052Y35539D01*
X213850Y35559D01*
X212875Y35463D01*
X212301Y35289D01*
X211714Y35172D01*
X209911Y34425D01*
X208588Y33541D01*
X207209Y32162D01*
X207209Y32162D01*
X206325Y30839D01*
X205578Y29036D01*
X205571Y29000D01*
X177513D01*
X176309Y29400D01*
X176193Y30570D01*
X176019Y31144D01*
X175902Y31731D01*
X175007Y33894D01*
X174123Y35217D01*
X172467Y36872D01*
X171144Y37757D01*
X171144Y37757D01*
X168981Y38652D01*
X168981Y38653D01*
X167421Y38963D01*
X165079D01*
X163519Y38653D01*
X163519Y38652D01*
X161356Y37757D01*
X160033Y36872D01*
X158377Y35217D01*
X157493Y33894D01*
X157493Y33894D01*
X156597Y31731D01*
X156481Y31144D01*
X156307Y30570D01*
X156191Y29400D01*
X154987Y29000D01*
X14429D01*
X14422Y29036D01*
X13675Y30838D01*
X12791Y32162D01*
X11412Y33541D01*
X11412Y33541D01*
X10088Y34425D01*
X10088Y34425D01*
X8286Y35172D01*
X7699Y35289D01*
X7125Y35463D01*
X6150Y35559D01*
X5948Y35539D01*
X5750Y35578D01*
X4078D01*
Y37982D01*
X5348Y38830D01*
X5739Y38669D01*
X7052D01*
X8266Y39172D01*
X8795Y39701D01*
X9573Y39980D01*
X10409Y39713D01*
X10921Y39201D01*
X12134Y38698D01*
X13448D01*
X14662Y39201D01*
X15590Y40130D01*
X16093Y41343D01*
Y42657D01*
X15590Y43870D01*
X14662Y44799D01*
X13448Y45302D01*
X12134D01*
X10921Y44799D01*
X10392Y44270D01*
X9613Y43991D01*
X8778Y44258D01*
X8266Y44770D01*
X7052Y45273D01*
X5781D01*
X5699Y45302D01*
X4656Y46078D01*
X4669Y46370D01*
X5917Y47114D01*
X6169Y47010D01*
X7482D01*
X8696Y47512D01*
X9625Y48441D01*
X10128Y49655D01*
Y50969D01*
X9625Y52182D01*
X8696Y53111D01*
X7482Y53614D01*
X6169D01*
X5348Y53274D01*
X4078Y53894D01*
X4078Y415922D01*
X63000D01*
Y413000D01*
D02*
G37*
%LPC*%
G36*
X149680Y337477D02*
X148367D01*
X147153Y336975D01*
X146224Y336046D01*
X145722Y334832D01*
Y333518D01*
X146224Y332305D01*
X147153Y331376D01*
X148367Y330873D01*
X149680D01*
X150894Y331376D01*
X151823Y332305D01*
X152326Y333518D01*
Y334832D01*
X151823Y336046D01*
X150894Y336975D01*
X149680Y337477D01*
D02*
G37*
G36*
X127566Y337334D02*
X126252D01*
X125039Y336831D01*
X124110Y335902D01*
X123607Y334688D01*
Y333375D01*
X124110Y332161D01*
X125039Y331232D01*
X126252Y330730D01*
X127566D01*
X128779Y331232D01*
X129708Y332161D01*
X130211Y333375D01*
Y334688D01*
X129708Y335902D01*
X128779Y336831D01*
X127566Y337334D01*
D02*
G37*
G36*
X138480Y336616D02*
X137166D01*
X135952Y336113D01*
X135023Y335184D01*
X134521Y333970D01*
Y332657D01*
X135023Y331443D01*
X135952Y330514D01*
X137166Y330012D01*
X138480D01*
X139693Y330514D01*
X140622Y331443D01*
X141125Y332657D01*
Y333970D01*
X140622Y335184D01*
X139693Y336113D01*
X138480Y336616D01*
D02*
G37*
G36*
X210657Y316402D02*
X209343D01*
X208130Y315899D01*
X207201Y314970D01*
X206698Y313757D01*
Y312443D01*
X207201Y311230D01*
X208130Y310301D01*
X209343Y309798D01*
X210657D01*
X211870Y310301D01*
X212799Y311230D01*
X213302Y312443D01*
Y313757D01*
X212799Y314970D01*
X211870Y315899D01*
X210657Y316402D01*
D02*
G37*
G36*
Y305402D02*
X209343D01*
X208130Y304899D01*
X207201Y303971D01*
X206698Y302757D01*
Y301443D01*
X207201Y300230D01*
X208130Y299301D01*
X209343Y298798D01*
X210657D01*
X211870Y299301D01*
X212799Y300230D01*
X213302Y301443D01*
Y302757D01*
X212799Y303971D01*
X211870Y304899D01*
X210657Y305402D01*
D02*
G37*
G36*
X14948Y413180D02*
X13634D01*
X12420Y412677D01*
X11491Y411748D01*
X10989Y410535D01*
Y409221D01*
X11491Y408007D01*
X12420Y407079D01*
X13634Y406576D01*
X14948D01*
X16161Y407079D01*
X17090Y408007D01*
X17593Y409221D01*
Y410535D01*
X17090Y411748D01*
X16161Y412677D01*
X14948Y413180D01*
D02*
G37*
G36*
X11808Y405131D02*
X10495D01*
X9281Y404628D01*
X8352Y403699D01*
X7849Y402485D01*
Y401172D01*
X8352Y399958D01*
X9281Y399029D01*
X10495Y398526D01*
X11808D01*
X13022Y399029D01*
X13366Y399373D01*
X14494Y399608D01*
X14960Y399308D01*
X15560Y398708D01*
X16774Y398205D01*
X18087D01*
X19301Y398708D01*
X19368Y398775D01*
X20587Y399152D01*
X21516Y398224D01*
X22729Y397721D01*
X24043D01*
X25257Y398224D01*
X26186Y399152D01*
X26688Y400366D01*
Y401680D01*
X26186Y402893D01*
X25257Y403822D01*
X24043Y404325D01*
X22729D01*
X21516Y403822D01*
X21448Y403755D01*
X20230Y403377D01*
X19301Y404306D01*
X18087Y404809D01*
X16774D01*
X15560Y404306D01*
X15216Y403963D01*
X14088Y403727D01*
X13622Y404028D01*
X13022Y404628D01*
X11808Y405131D01*
D02*
G37*
G36*
X51052Y380776D02*
X49739D01*
X48525Y380273D01*
X47596Y379344D01*
X47094Y378130D01*
Y376817D01*
X47596Y375603D01*
X48435Y374764D01*
X48527Y374637D01*
X48599Y373269D01*
X48201Y372870D01*
X47698Y371657D01*
Y370343D01*
X48201Y369130D01*
X49130Y368201D01*
X50343Y367698D01*
X51657D01*
X52870Y368201D01*
X53799Y369130D01*
X54302Y370343D01*
Y371657D01*
X53799Y372870D01*
X52960Y373709D01*
X52868Y373837D01*
X52796Y375205D01*
X53195Y375603D01*
X53698Y376817D01*
Y378130D01*
X53195Y379344D01*
X52266Y380273D01*
X51052Y380776D01*
D02*
G37*
G36*
X54631Y362951D02*
X53317D01*
X52104Y362449D01*
X51175Y361520D01*
X50672Y360306D01*
Y358992D01*
X51175Y357779D01*
X52104Y356850D01*
X53317Y356347D01*
X54631D01*
X55844Y356850D01*
X56773Y357779D01*
X57276Y358992D01*
Y360306D01*
X56773Y361520D01*
X55844Y362449D01*
X54631Y362951D01*
D02*
G37*
G36*
X26657Y352302D02*
X25343D01*
X24130Y351799D01*
X23201Y350870D01*
X22698Y349657D01*
Y348343D01*
X23201Y347130D01*
X24130Y346201D01*
X25343Y345698D01*
X26657D01*
X27870Y346201D01*
X28799Y347130D01*
X29302Y348343D01*
Y349657D01*
X28799Y350870D01*
X27870Y351799D01*
X26657Y352302D01*
D02*
G37*
G36*
X11657D02*
X10343D01*
X9130Y351799D01*
X8201Y350870D01*
X7698Y349657D01*
Y348343D01*
X8201Y347130D01*
X9130Y346201D01*
X10343Y345698D01*
X11657D01*
X12870Y346201D01*
X13799Y347130D01*
X14302Y348343D01*
Y349657D01*
X13799Y350870D01*
X12870Y351799D01*
X11657Y352302D01*
D02*
G37*
G36*
X19176Y347296D02*
X17862D01*
X16648Y346794D01*
X15720Y345865D01*
X15217Y344651D01*
Y343338D01*
X15720Y342124D01*
X16648Y341195D01*
X17862Y340692D01*
X19176D01*
X20389Y341195D01*
X21318Y342124D01*
X21821Y343338D01*
Y344651D01*
X21318Y345865D01*
X20389Y346794D01*
X19176Y347296D01*
D02*
G37*
G36*
X58657Y302902D02*
X57343D01*
X56130Y302399D01*
X55201Y301471D01*
X54698Y300257D01*
Y298943D01*
X55201Y297730D01*
X56130Y296801D01*
X57343Y296298D01*
X58657D01*
X59870Y296801D01*
X60799Y297730D01*
X61302Y298943D01*
Y300257D01*
X60799Y301471D01*
X59870Y302399D01*
X58657Y302902D01*
D02*
G37*
G36*
X37657D02*
X36343D01*
X35130Y302399D01*
X34201Y301471D01*
X33698Y300257D01*
Y298943D01*
X34201Y297730D01*
X35130Y296801D01*
X36343Y296298D01*
X37657D01*
X38870Y296801D01*
X39799Y297730D01*
X40302Y298943D01*
Y300257D01*
X39799Y301471D01*
X38870Y302399D01*
X37657Y302902D01*
D02*
G37*
G36*
X58657Y281902D02*
X57343D01*
X56130Y281399D01*
X55201Y280471D01*
X54698Y279257D01*
Y277943D01*
X55201Y276730D01*
X56130Y275801D01*
X57343Y275298D01*
X58657D01*
X59870Y275801D01*
X60799Y276730D01*
X61302Y277943D01*
Y279257D01*
X60799Y280471D01*
X59870Y281399D01*
X58657Y281902D01*
D02*
G37*
G36*
X37657D02*
X36343D01*
X35130Y281399D01*
X34201Y280471D01*
X33698Y279257D01*
Y277943D01*
X34201Y276730D01*
X35130Y275801D01*
X36343Y275298D01*
X37657D01*
X38870Y275801D01*
X39799Y276730D01*
X40302Y277943D01*
Y279257D01*
X39799Y280471D01*
X38870Y281399D01*
X37657Y281902D01*
D02*
G37*
G36*
X210657Y261402D02*
X209343D01*
X208130Y260899D01*
X207201Y259970D01*
X206698Y258757D01*
Y257443D01*
X207201Y256230D01*
X208130Y255301D01*
X209343Y254798D01*
X210657D01*
X211870Y255301D01*
X212799Y256230D01*
X213302Y257443D01*
Y258757D01*
X212799Y259970D01*
X211870Y260899D01*
X210657Y261402D01*
D02*
G37*
G36*
X163657Y260302D02*
X162343D01*
X161130Y259799D01*
X160201Y258870D01*
X159698Y257657D01*
Y256343D01*
X160201Y255130D01*
X161130Y254201D01*
X162343Y253698D01*
X163657D01*
X164870Y254201D01*
X165799Y255130D01*
X166302Y256343D01*
Y257657D01*
X165799Y258870D01*
X164870Y259799D01*
X163657Y260302D01*
D02*
G37*
G36*
X142657D02*
X141343D01*
X140130Y259799D01*
X139201Y258870D01*
X138698Y257657D01*
Y256343D01*
X139201Y255130D01*
X140130Y254201D01*
X141343Y253698D01*
X142657D01*
X143870Y254201D01*
X144799Y255130D01*
X145302Y256343D01*
Y257657D01*
X144799Y258870D01*
X143870Y259799D01*
X142657Y260302D01*
D02*
G37*
G36*
X121657D02*
X120343D01*
X119130Y259799D01*
X118201Y258870D01*
X117698Y257657D01*
Y256343D01*
X118201Y255130D01*
X119130Y254201D01*
X120343Y253698D01*
X121657D01*
X122870Y254201D01*
X123799Y255130D01*
X124302Y256343D01*
Y257657D01*
X123799Y258870D01*
X122870Y259799D01*
X121657Y260302D01*
D02*
G37*
G36*
X79657D02*
X78343D01*
X77130Y259799D01*
X76201Y258870D01*
X75698Y257657D01*
Y256343D01*
X76201Y255130D01*
X77130Y254201D01*
X78343Y253698D01*
X79657D01*
X80871Y254201D01*
X81799Y255130D01*
X82302Y256343D01*
Y257657D01*
X81799Y258870D01*
X80871Y259799D01*
X79657Y260302D01*
D02*
G37*
G36*
X58657D02*
X57343D01*
X56130Y259799D01*
X55201Y258870D01*
X54698Y257657D01*
Y256343D01*
X55201Y255130D01*
X56130Y254201D01*
X57343Y253698D01*
X58657D01*
X59870Y254201D01*
X60799Y255130D01*
X61302Y256343D01*
Y257657D01*
X60799Y258870D01*
X59870Y259799D01*
X58657Y260302D01*
D02*
G37*
G36*
X37657D02*
X36343D01*
X35130Y259799D01*
X34201Y258870D01*
X33698Y257657D01*
Y256343D01*
X34201Y255130D01*
X35130Y254201D01*
X36343Y253698D01*
X37657D01*
X38870Y254201D01*
X39799Y255130D01*
X40302Y256343D01*
Y257657D01*
X39799Y258870D01*
X38870Y259799D01*
X37657Y260302D01*
D02*
G37*
G36*
X184657Y260302D02*
X183343D01*
X182130Y259799D01*
X181201Y258870D01*
X180698Y257657D01*
Y256343D01*
X181201Y255130D01*
X182130Y254201D01*
X183343Y253698D01*
X184657D01*
X185870Y254201D01*
X186799Y255130D01*
X187302Y256343D01*
Y257657D01*
X186799Y258870D01*
X185870Y259799D01*
X184657Y260302D01*
D02*
G37*
G36*
X100657Y259702D02*
X99343D01*
X98130Y259199D01*
X97201Y258270D01*
X96698Y257057D01*
Y255743D01*
X97201Y254529D01*
X98130Y253601D01*
X99343Y253098D01*
X100657D01*
X101870Y253601D01*
X102799Y254529D01*
X103302Y255743D01*
Y257057D01*
X102799Y258270D01*
X101870Y259199D01*
X100657Y259702D01*
D02*
G37*
G36*
X163657Y239902D02*
X162343D01*
X161130Y239400D01*
X160201Y238471D01*
X159698Y237257D01*
Y235943D01*
X160201Y234730D01*
X161130Y233801D01*
X162343Y233298D01*
X163657D01*
X164870Y233801D01*
X165799Y234730D01*
X166302Y235943D01*
Y237257D01*
X165799Y238471D01*
X164870Y239400D01*
X163657Y239902D01*
D02*
G37*
G36*
X142657D02*
X141343D01*
X140130Y239400D01*
X139201Y238471D01*
X138698Y237257D01*
Y235943D01*
X139201Y234730D01*
X140130Y233801D01*
X141343Y233298D01*
X142657D01*
X143870Y233801D01*
X144799Y234730D01*
X145302Y235943D01*
Y237257D01*
X144799Y238471D01*
X143870Y239400D01*
X142657Y239902D01*
D02*
G37*
G36*
X121657D02*
X120343D01*
X119130Y239400D01*
X118201Y238471D01*
X117698Y237257D01*
Y235943D01*
X118201Y234730D01*
X119130Y233801D01*
X120343Y233298D01*
X121657D01*
X122870Y233801D01*
X123799Y234730D01*
X124302Y235943D01*
Y237257D01*
X123799Y238471D01*
X122870Y239400D01*
X121657Y239902D01*
D02*
G37*
G36*
X79657D02*
X78343D01*
X77130Y239400D01*
X76201Y238471D01*
X75698Y237257D01*
Y235943D01*
X76201Y234730D01*
X77130Y233801D01*
X78343Y233298D01*
X79657D01*
X80871Y233801D01*
X81799Y234730D01*
X82302Y235943D01*
Y237257D01*
X81799Y238471D01*
X80871Y239400D01*
X79657Y239902D01*
D02*
G37*
G36*
X58657D02*
X57343D01*
X56130Y239400D01*
X55201Y238471D01*
X54698Y237257D01*
Y235943D01*
X55201Y234730D01*
X56130Y233801D01*
X57343Y233298D01*
X58657D01*
X59870Y233801D01*
X60799Y234730D01*
X61302Y235943D01*
Y237257D01*
X60799Y238471D01*
X59870Y239400D01*
X58657Y239902D01*
D02*
G37*
G36*
X37657D02*
X36343D01*
X35130Y239400D01*
X34201Y238471D01*
X33698Y237257D01*
Y235943D01*
X34201Y234730D01*
X35130Y233801D01*
X36343Y233298D01*
X37657D01*
X38870Y233801D01*
X39799Y234730D01*
X40302Y235943D01*
Y237257D01*
X39799Y238471D01*
X38870Y239400D01*
X37657Y239902D01*
D02*
G37*
G36*
X184657Y239902D02*
X183343D01*
X182130Y239400D01*
X181201Y238471D01*
X180698Y237257D01*
Y235943D01*
X181201Y234730D01*
X182130Y233801D01*
X183343Y233298D01*
X184657D01*
X185870Y233801D01*
X186799Y234730D01*
X187302Y235943D01*
Y237257D01*
X186799Y238471D01*
X185870Y239400D01*
X184657Y239902D01*
D02*
G37*
G36*
X210657Y239402D02*
X209343D01*
X208130Y238899D01*
X207201Y237971D01*
X206698Y236757D01*
Y235443D01*
X207201Y234230D01*
X208130Y233301D01*
X209343Y232798D01*
X210657D01*
X211870Y233301D01*
X212799Y234230D01*
X213302Y235443D01*
Y236757D01*
X212799Y237971D01*
X211870Y238899D01*
X210657Y239402D01*
D02*
G37*
G36*
X100657Y239302D02*
X99343D01*
X98130Y238799D01*
X97201Y237871D01*
X96698Y236657D01*
Y235343D01*
X97201Y234130D01*
X98130Y233201D01*
X99343Y232698D01*
X100657D01*
X101870Y233201D01*
X102799Y234130D01*
X103302Y235343D01*
Y236657D01*
X102799Y237871D01*
X101870Y238799D01*
X100657Y239302D01*
D02*
G37*
G36*
X163657Y218902D02*
X162343D01*
X161130Y218400D01*
X160201Y217471D01*
X159698Y216257D01*
Y214944D01*
X160201Y213730D01*
X161130Y212801D01*
X162343Y212298D01*
X163657D01*
X164870Y212801D01*
X165799Y213730D01*
X166302Y214944D01*
Y216257D01*
X165799Y217471D01*
X164870Y218400D01*
X163657Y218902D01*
D02*
G37*
G36*
X142657D02*
X141343D01*
X140130Y218400D01*
X139201Y217471D01*
X138698Y216257D01*
Y214944D01*
X139201Y213730D01*
X140130Y212801D01*
X141343Y212298D01*
X142657D01*
X143870Y212801D01*
X144799Y213730D01*
X145302Y214944D01*
Y216257D01*
X144799Y217471D01*
X143870Y218400D01*
X142657Y218902D01*
D02*
G37*
G36*
X121657D02*
X120343D01*
X119130Y218400D01*
X118201Y217471D01*
X117698Y216257D01*
Y214944D01*
X118201Y213730D01*
X119130Y212801D01*
X120343Y212298D01*
X121657D01*
X122870Y212801D01*
X123799Y213730D01*
X124302Y214944D01*
Y216257D01*
X123799Y217471D01*
X122870Y218400D01*
X121657Y218902D01*
D02*
G37*
G36*
X79657D02*
X78343D01*
X77130Y218400D01*
X76201Y217471D01*
X75698Y216257D01*
Y214944D01*
X76201Y213730D01*
X77130Y212801D01*
X78343Y212298D01*
X79657D01*
X80871Y212801D01*
X81799Y213730D01*
X82302Y214944D01*
Y216257D01*
X81799Y217471D01*
X80871Y218400D01*
X79657Y218902D01*
D02*
G37*
G36*
X58657D02*
X57343D01*
X56130Y218400D01*
X55201Y217471D01*
X54698Y216257D01*
Y214944D01*
X55201Y213730D01*
X56130Y212801D01*
X57343Y212298D01*
X58657D01*
X59870Y212801D01*
X60799Y213730D01*
X61302Y214944D01*
Y216257D01*
X60799Y217471D01*
X59870Y218400D01*
X58657Y218902D01*
D02*
G37*
G36*
X37657D02*
X36343D01*
X35130Y218400D01*
X34201Y217471D01*
X33698Y216257D01*
Y214944D01*
X34201Y213730D01*
X35130Y212801D01*
X36343Y212298D01*
X37657D01*
X38870Y212801D01*
X39799Y213730D01*
X40302Y214944D01*
Y216257D01*
X39799Y217471D01*
X38870Y218400D01*
X37657Y218902D01*
D02*
G37*
G36*
X184657Y218902D02*
X183343D01*
X182130Y218400D01*
X181201Y217471D01*
X180698Y216257D01*
Y214943D01*
X181201Y213730D01*
X182130Y212801D01*
X183343Y212298D01*
X184657D01*
X185870Y212801D01*
X186799Y213730D01*
X187302Y214943D01*
Y216257D01*
X186799Y217471D01*
X185870Y218400D01*
X184657Y218902D01*
D02*
G37*
G36*
X100657Y218302D02*
X99343D01*
X98130Y217799D01*
X97201Y216871D01*
X96698Y215657D01*
Y214343D01*
X97201Y213130D01*
X98130Y212201D01*
X99343Y211698D01*
X100657D01*
X101870Y212201D01*
X102799Y213130D01*
X103302Y214343D01*
Y215657D01*
X102799Y216871D01*
X101870Y217799D01*
X100657Y218302D01*
D02*
G37*
G36*
X210657Y217402D02*
X209343D01*
X208130Y216899D01*
X207201Y215970D01*
X206698Y214757D01*
Y213443D01*
X207201Y212230D01*
X208130Y211301D01*
X209343Y210798D01*
X210657D01*
X211870Y211301D01*
X212799Y212230D01*
X213302Y213443D01*
Y214757D01*
X212799Y215970D01*
X211870Y216899D01*
X210657Y217402D01*
D02*
G37*
G36*
Y206402D02*
X209343D01*
X208130Y205899D01*
X207201Y204970D01*
X206698Y203757D01*
Y202443D01*
X207201Y201230D01*
X208130Y200301D01*
X209343Y199798D01*
X210657D01*
X211870Y200301D01*
X212799Y201230D01*
X213302Y202443D01*
Y203757D01*
X212799Y204970D01*
X211870Y205899D01*
X210657Y206402D01*
D02*
G37*
G36*
X163657Y197902D02*
X162343D01*
X161130Y197400D01*
X160201Y196471D01*
X159698Y195257D01*
Y193944D01*
X160201Y192730D01*
X161130Y191801D01*
X162343Y191298D01*
X163657D01*
X164870Y191801D01*
X165799Y192730D01*
X166302Y193944D01*
Y195257D01*
X165799Y196471D01*
X164870Y197400D01*
X163657Y197902D01*
D02*
G37*
G36*
X142657D02*
X141343D01*
X140130Y197400D01*
X139201Y196471D01*
X138698Y195257D01*
Y193944D01*
X139201Y192730D01*
X140130Y191801D01*
X141343Y191298D01*
X142657D01*
X143870Y191801D01*
X144799Y192730D01*
X145302Y193944D01*
Y195257D01*
X144799Y196471D01*
X143870Y197400D01*
X142657Y197902D01*
D02*
G37*
G36*
X121657D02*
X120343D01*
X119130Y197400D01*
X118201Y196471D01*
X117698Y195257D01*
Y193944D01*
X118201Y192730D01*
X119130Y191801D01*
X120343Y191298D01*
X121657D01*
X122870Y191801D01*
X123799Y192730D01*
X124302Y193944D01*
Y195257D01*
X123799Y196471D01*
X122870Y197400D01*
X121657Y197902D01*
D02*
G37*
G36*
X79657D02*
X78343D01*
X77130Y197400D01*
X76201Y196471D01*
X75698Y195257D01*
Y193944D01*
X76201Y192730D01*
X77130Y191801D01*
X78343Y191298D01*
X79657D01*
X80871Y191801D01*
X81799Y192730D01*
X82302Y193944D01*
Y195257D01*
X81799Y196471D01*
X80871Y197400D01*
X79657Y197902D01*
D02*
G37*
G36*
X58657D02*
X57343D01*
X56130Y197400D01*
X55201Y196471D01*
X54698Y195257D01*
Y193944D01*
X55201Y192730D01*
X56130Y191801D01*
X57343Y191298D01*
X58657D01*
X59870Y191801D01*
X60799Y192730D01*
X61302Y193944D01*
Y195257D01*
X60799Y196471D01*
X59870Y197400D01*
X58657Y197902D01*
D02*
G37*
G36*
X37657D02*
X36343D01*
X35130Y197400D01*
X34201Y196471D01*
X33698Y195257D01*
Y193944D01*
X34201Y192730D01*
X35130Y191801D01*
X36343Y191298D01*
X37657D01*
X38870Y191801D01*
X39799Y192730D01*
X40302Y193944D01*
Y195257D01*
X39799Y196471D01*
X38870Y197400D01*
X37657Y197902D01*
D02*
G37*
G36*
X184657Y197902D02*
X183343D01*
X182130Y197400D01*
X181201Y196471D01*
X180698Y195257D01*
Y193944D01*
X181201Y192730D01*
X182130Y191801D01*
X183343Y191298D01*
X184657D01*
X185870Y191801D01*
X186799Y192730D01*
X187302Y193944D01*
Y195257D01*
X186799Y196471D01*
X185870Y197400D01*
X184657Y197902D01*
D02*
G37*
G36*
X100657Y197302D02*
X99343D01*
X98130Y196800D01*
X97201Y195871D01*
X96698Y194657D01*
Y193343D01*
X97201Y192130D01*
X98130Y191201D01*
X99343Y190698D01*
X100657D01*
X101870Y191201D01*
X102799Y192130D01*
X103302Y193343D01*
Y194657D01*
X102799Y195871D01*
X101870Y196800D01*
X100657Y197302D01*
D02*
G37*
G36*
X210657Y195402D02*
X209343D01*
X208130Y194899D01*
X207201Y193971D01*
X206698Y192757D01*
Y191443D01*
X207201Y190230D01*
X208130Y189301D01*
X209343Y188798D01*
X210657D01*
X211870Y189301D01*
X212799Y190230D01*
X213302Y191443D01*
Y192757D01*
X212799Y193971D01*
X211870Y194899D01*
X210657Y195402D01*
D02*
G37*
G36*
Y184402D02*
X209343D01*
X208130Y183899D01*
X207201Y182971D01*
X206698Y181757D01*
Y180443D01*
X207201Y179230D01*
X208130Y178301D01*
X209343Y177798D01*
X210657D01*
X211870Y178301D01*
X212799Y179230D01*
X213302Y180443D01*
Y181757D01*
X212799Y182971D01*
X211870Y183899D01*
X210657Y184402D01*
D02*
G37*
G36*
X138919Y165406D02*
X137605D01*
X136391Y164903D01*
X135463Y163974D01*
X134960Y162760D01*
Y161447D01*
X135463Y160233D01*
X136391Y159304D01*
X137605Y158801D01*
X138919D01*
X140132Y159304D01*
X141061Y160233D01*
X141564Y161447D01*
Y162760D01*
X141061Y163974D01*
X140132Y164903D01*
X138919Y165406D01*
D02*
G37*
G36*
X83885D02*
X82571D01*
X81358Y164903D01*
X80429Y163974D01*
X79926Y162760D01*
Y161447D01*
X80429Y160233D01*
X81358Y159304D01*
X82571Y158801D01*
X83885D01*
X85099Y159304D01*
X86027Y160233D01*
X86530Y161447D01*
Y162760D01*
X86027Y163974D01*
X85099Y164903D01*
X83885Y165406D01*
D02*
G37*
G36*
X182482Y164744D02*
X181169D01*
X179955Y164241D01*
X179026Y163312D01*
X178524Y162099D01*
Y160785D01*
X179026Y159571D01*
X179955Y158642D01*
X181169Y158140D01*
X182482D01*
X183696Y158642D01*
X184625Y159571D01*
X185128Y160785D01*
Y162099D01*
X184625Y163312D01*
X183696Y164241D01*
X182482Y164744D01*
D02*
G37*
G36*
X149506Y164523D02*
X148193D01*
X146979Y164021D01*
X146050Y163092D01*
X145548Y161878D01*
Y160564D01*
X146050Y159351D01*
X146979Y158422D01*
X148193Y157919D01*
X149506D01*
X150720Y158422D01*
X151649Y159351D01*
X152151Y160564D01*
Y161878D01*
X151649Y163092D01*
X150720Y164021D01*
X149506Y164523D01*
D02*
G37*
G36*
X83657Y149302D02*
X82343D01*
X81130Y148799D01*
X80201Y147870D01*
X79698Y146657D01*
Y145343D01*
X80201Y144130D01*
X81130Y143201D01*
X82343Y142698D01*
X83657D01*
X84870Y143201D01*
X85799Y144130D01*
X86302Y145343D01*
Y146657D01*
X85799Y147870D01*
X84870Y148799D01*
X83657Y149302D01*
D02*
G37*
G36*
X145683Y148482D02*
X144370D01*
X143156Y147979D01*
X142227Y147050D01*
X141725Y145837D01*
Y144523D01*
X142227Y143309D01*
X143156Y142381D01*
X144370Y141878D01*
X145683D01*
X146897Y142381D01*
X147826Y143309D01*
X148329Y144523D01*
Y145837D01*
X147826Y147050D01*
X146897Y147979D01*
X145683Y148482D01*
D02*
G37*
G36*
X115657Y149302D02*
X114343D01*
X113130Y148799D01*
X112201Y147870D01*
X111698Y146657D01*
Y145343D01*
X112201Y144130D01*
X113130Y143201D01*
X113162Y143187D01*
Y141813D01*
X113130Y141799D01*
X112201Y140870D01*
X111698Y139657D01*
Y138343D01*
X112201Y137130D01*
X113130Y136201D01*
X114343Y135698D01*
X115657D01*
X116870Y136201D01*
X117799Y137130D01*
X118302Y138343D01*
Y139657D01*
X117799Y140870D01*
X116870Y141799D01*
X116838Y141813D01*
Y143187D01*
X116870Y143201D01*
X117799Y144130D01*
X118302Y145343D01*
Y146657D01*
X117799Y147870D01*
X116870Y148799D01*
X115657Y149302D01*
D02*
G37*
G36*
X168657Y134302D02*
X167343D01*
X166130Y133799D01*
X165201Y132870D01*
X164698Y131657D01*
Y130343D01*
X165201Y129130D01*
X166130Y128201D01*
X167343Y127698D01*
X168657D01*
X169870Y128201D01*
X170799Y129130D01*
X171302Y130343D01*
Y131657D01*
X170799Y132870D01*
X169870Y133799D01*
X168657Y134302D01*
D02*
G37*
G36*
X40109Y133953D02*
X38795D01*
X37582Y133450D01*
X36653Y132521D01*
X36150Y131307D01*
Y129994D01*
X36653Y128780D01*
X37582Y127851D01*
X38795Y127348D01*
X40109D01*
X41322Y127851D01*
X42251Y128780D01*
X42754Y129994D01*
Y131307D01*
X42251Y132521D01*
X41322Y133450D01*
X40109Y133953D01*
D02*
G37*
G36*
X77268Y130474D02*
X75954D01*
X74740Y129972D01*
X73812Y129043D01*
X73309Y127829D01*
Y126515D01*
X73812Y125302D01*
X74740Y124373D01*
X75954Y123870D01*
X77268D01*
X78481Y124373D01*
X79410Y125302D01*
X79913Y126515D01*
Y127829D01*
X79410Y129043D01*
X78481Y129972D01*
X77268Y130474D01*
D02*
G37*
G36*
X53708Y130031D02*
X52394D01*
X51180Y129528D01*
X50251Y128599D01*
X49749Y127386D01*
Y126072D01*
X50251Y124859D01*
X51180Y123930D01*
X52394Y123427D01*
X53708D01*
X54921Y123930D01*
X55850Y124859D01*
X56353Y126072D01*
Y127386D01*
X55850Y128599D01*
X54921Y129528D01*
X53708Y130031D01*
D02*
G37*
G36*
X201657Y123302D02*
X200343D01*
X199130Y122799D01*
X198201Y121870D01*
X197698Y120657D01*
Y119343D01*
X198201Y118130D01*
X199130Y117201D01*
X200343Y116698D01*
X201657D01*
X202870Y117201D01*
X203799Y118130D01*
X204302Y119343D01*
Y120657D01*
X203799Y121870D01*
X202870Y122799D01*
X201657Y123302D01*
D02*
G37*
G36*
X167657D02*
X166343D01*
X165130Y122799D01*
X164201Y121870D01*
X163698Y120657D01*
Y119343D01*
X164201Y118130D01*
X165130Y117201D01*
X166343Y116698D01*
X167657D01*
X168870Y117201D01*
X169799Y118130D01*
X170302Y119343D01*
Y120657D01*
X169799Y121870D01*
X168870Y122799D01*
X167657Y123302D01*
D02*
G37*
G36*
X95450Y115521D02*
X94137D01*
X92923Y115018D01*
X91994Y114089D01*
X91491Y112875D01*
Y111562D01*
X91994Y110348D01*
X92923Y109419D01*
X94137Y108917D01*
X95450D01*
X96664Y109419D01*
X97593Y110348D01*
X98095Y111562D01*
Y112875D01*
X97593Y114089D01*
X96664Y115018D01*
X95450Y115521D01*
D02*
G37*
G36*
X166657Y115302D02*
X165343D01*
X164130Y114799D01*
X163201Y113870D01*
X162698Y112657D01*
Y111343D01*
X163201Y110130D01*
X164130Y109201D01*
X165343Y108698D01*
X166657D01*
X167870Y109201D01*
X168799Y110130D01*
X169302Y111343D01*
Y112657D01*
X168799Y113870D01*
X167870Y114799D01*
X166657Y115302D01*
D02*
G37*
G36*
X66657D02*
X65343D01*
X64130Y114799D01*
X63201Y113870D01*
X62698Y112657D01*
Y111343D01*
X63201Y110130D01*
X64130Y109201D01*
X65343Y108698D01*
X66657D01*
X67870Y109201D01*
X68799Y110130D01*
X69302Y111343D01*
Y112657D01*
X68799Y113870D01*
X67870Y114799D01*
X66657Y115302D01*
D02*
G37*
G36*
X204657Y114302D02*
X203343D01*
X202130Y113799D01*
X201201Y112870D01*
X200698Y111657D01*
Y110343D01*
X201201Y109130D01*
X202130Y108201D01*
X203343Y107698D01*
X204657D01*
X205870Y108201D01*
X206799Y109130D01*
X207302Y110343D01*
Y111657D01*
X206799Y112870D01*
X205870Y113799D01*
X204657Y114302D01*
D02*
G37*
G36*
X104657Y110302D02*
X103343D01*
X102130Y109799D01*
X101201Y108870D01*
X100698Y107657D01*
Y106343D01*
X101201Y105130D01*
X102130Y104201D01*
X103343Y103698D01*
X104657D01*
X105870Y104201D01*
X106799Y105130D01*
X107302Y106343D01*
Y107657D01*
X106799Y108870D01*
X105870Y109799D01*
X104657Y110302D01*
D02*
G37*
G36*
X155030Y109298D02*
X153716D01*
X152503Y108796D01*
X151574Y107867D01*
X151071Y106653D01*
Y105340D01*
X151574Y104126D01*
X152503Y103197D01*
X153716Y102695D01*
X155030D01*
X156244Y103197D01*
X157173Y104126D01*
X157675Y105340D01*
Y106653D01*
X157173Y107867D01*
X156244Y108796D01*
X155030Y109298D01*
D02*
G37*
G36*
X93714Y104897D02*
X92400D01*
X91187Y104395D01*
X90258Y103466D01*
X89755Y102252D01*
Y100939D01*
X90258Y99725D01*
X91187Y98796D01*
X92400Y98293D01*
X93714D01*
X94927Y98796D01*
X95856Y99725D01*
X96359Y100939D01*
Y102252D01*
X95856Y103466D01*
X94927Y104395D01*
X93714Y104897D01*
D02*
G37*
G36*
X66645Y103671D02*
X65332D01*
X64118Y103168D01*
X63189Y102240D01*
X62686Y101026D01*
Y99712D01*
X63189Y98499D01*
X64118Y97570D01*
X65332Y97067D01*
X66645D01*
X67859Y97570D01*
X68788Y98499D01*
X69290Y99712D01*
Y101026D01*
X68788Y102240D01*
X67859Y103168D01*
X66645Y103671D01*
D02*
G37*
G36*
X126657Y103302D02*
X125343D01*
X124130Y102799D01*
X123201Y101870D01*
X122698Y100657D01*
Y99343D01*
X123201Y98130D01*
X124130Y97201D01*
X125343Y96698D01*
X126657D01*
X127870Y97201D01*
X128799Y98130D01*
X129302Y99343D01*
Y100657D01*
X128799Y101870D01*
X127870Y102799D01*
X126657Y103302D01*
D02*
G37*
G36*
X90819Y88876D02*
X89506D01*
X88292Y88373D01*
X87363Y87444D01*
X86861Y86231D01*
Y84917D01*
X87363Y83704D01*
X88292Y82775D01*
X89506Y82272D01*
X90819D01*
X92033Y82775D01*
X92962Y83704D01*
X93464Y84917D01*
Y86231D01*
X92962Y87444D01*
X92033Y88373D01*
X90819Y88876D01*
D02*
G37*
G36*
X207657Y80302D02*
X206343D01*
X205130Y79799D01*
X204201Y78870D01*
X203698Y77657D01*
Y76343D01*
X204201Y75130D01*
X205130Y74201D01*
X206343Y73698D01*
X207657D01*
X208870Y74201D01*
X209799Y75130D01*
X210302Y76343D01*
Y77657D01*
X209799Y78870D01*
X208870Y79799D01*
X207657Y80302D01*
D02*
G37*
G36*
X198657D02*
X197343D01*
X196130Y79799D01*
X195201Y78870D01*
X194698Y77657D01*
Y76343D01*
X195201Y75130D01*
X196130Y74201D01*
X197343Y73698D01*
X198657D01*
X199870Y74201D01*
X200799Y75130D01*
X201302Y76343D01*
Y77657D01*
X200799Y78870D01*
X199870Y79799D01*
X198657Y80302D01*
D02*
G37*
G36*
X12657Y77302D02*
X11343D01*
X10130Y76799D01*
X9201Y75870D01*
X8698Y74657D01*
Y73343D01*
X9201Y72130D01*
X10130Y71201D01*
X11343Y70698D01*
X12657D01*
X13870Y71201D01*
X14799Y72130D01*
X15302Y73343D01*
Y74657D01*
X14799Y75870D01*
X13870Y76799D01*
X12657Y77302D01*
D02*
G37*
G36*
X81169Y70918D02*
X79855D01*
X78642Y70415D01*
X77713Y69486D01*
X77210Y68273D01*
Y66959D01*
X77713Y65745D01*
X78642Y64817D01*
X79855Y64314D01*
X81169D01*
X82382Y64817D01*
X83311Y65745D01*
X83814Y66959D01*
Y68273D01*
X83311Y69486D01*
X82382Y70415D01*
X81169Y70918D01*
D02*
G37*
G36*
X12657Y68302D02*
X11343D01*
X10130Y67799D01*
X9201Y66870D01*
X8698Y65657D01*
Y64343D01*
X9201Y63130D01*
X10130Y62201D01*
X11343Y61698D01*
X12657D01*
X13870Y62201D01*
X14799Y63130D01*
X15302Y64343D01*
Y65657D01*
X14799Y66870D01*
X13870Y67799D01*
X12657Y68302D01*
D02*
G37*
G36*
X107605Y65774D02*
X106292D01*
X105078Y65272D01*
X104149Y64343D01*
X103646Y63129D01*
Y61815D01*
X104149Y60602D01*
X105078Y59673D01*
X106292Y59170D01*
X107605D01*
X108819Y59673D01*
X109748Y60602D01*
X110250Y61815D01*
Y63129D01*
X109748Y64343D01*
X108819Y65272D01*
X107605Y65774D01*
D02*
G37*
G36*
X15657Y53614D02*
X14343D01*
X13130Y53111D01*
X12201Y52182D01*
X11698Y50969D01*
Y49655D01*
X12201Y48441D01*
X13130Y47512D01*
X14343Y47010D01*
X15657D01*
X16870Y47512D01*
X17799Y48441D01*
X18302Y49655D01*
Y50969D01*
X17799Y52182D01*
X16870Y53111D01*
X15657Y53614D01*
D02*
G37*
G36*
X176657Y47302D02*
X175343D01*
X174130Y46799D01*
X173201Y45870D01*
X172698Y44657D01*
Y43343D01*
X173201Y42130D01*
X174130Y41201D01*
X175343Y40698D01*
X176657D01*
X177870Y41201D01*
X178799Y42130D01*
X179302Y43343D01*
Y44657D01*
X178799Y45870D01*
X177870Y46799D01*
X176657Y47302D01*
D02*
G37*
G36*
X63657Y41302D02*
X62343D01*
X61130Y40799D01*
X60201Y39870D01*
X59698Y38657D01*
Y37343D01*
X60201Y36130D01*
X61130Y35201D01*
X62343Y34698D01*
X63657D01*
X64870Y35201D01*
X65799Y36130D01*
X66302Y37343D01*
Y38657D01*
X65799Y39870D01*
X64870Y40799D01*
X63657Y41302D01*
D02*
G37*
G36*
X191202Y47237D02*
X189888D01*
X188674Y46734D01*
X187745Y45806D01*
X187243Y44592D01*
Y43278D01*
X187745Y42065D01*
X188674Y41136D01*
X188856Y41061D01*
X188978Y40500D01*
X188969Y39639D01*
X188201Y38870D01*
X187698Y37657D01*
Y36343D01*
X188201Y35130D01*
X189130Y34201D01*
X190343Y33698D01*
X191657D01*
X192870Y34201D01*
X193799Y35130D01*
X194302Y36343D01*
Y37657D01*
X193799Y38870D01*
X192870Y39799D01*
X192689Y39875D01*
X192567Y40435D01*
X192575Y41296D01*
X193344Y42065D01*
X193847Y43278D01*
Y44592D01*
X193344Y45806D01*
X192415Y46734D01*
X191202Y47237D01*
D02*
G37*
G36*
X152657Y39302D02*
X151343D01*
X150130Y38799D01*
X149201Y37870D01*
X148698Y36657D01*
Y35343D01*
X149201Y34130D01*
X150130Y33201D01*
X151343Y32698D01*
X152657D01*
X153870Y33201D01*
X154799Y34130D01*
X155302Y35343D01*
Y36657D01*
X154799Y37870D01*
X153870Y38799D01*
X152657Y39302D01*
D02*
G37*
G36*
X137657D02*
X136343D01*
X135130Y38799D01*
X134201Y37870D01*
X133698Y36657D01*
Y35343D01*
X134201Y34130D01*
X135130Y33201D01*
X136343Y32698D01*
X137657D01*
X138870Y33201D01*
X139799Y34130D01*
X140302Y35343D01*
Y36657D01*
X139799Y37870D01*
X138870Y38799D01*
X137657Y39302D01*
D02*
G37*
G36*
X123657Y38302D02*
X122343D01*
X121130Y37799D01*
X120201Y36870D01*
X119698Y35657D01*
Y34343D01*
X120201Y33130D01*
X121130Y32201D01*
X122343Y31698D01*
X123657D01*
X124870Y32201D01*
X125799Y33130D01*
X126302Y34343D01*
Y35657D01*
X125799Y36870D01*
X124870Y37799D01*
X123657Y38302D01*
D02*
G37*
G36*
X111657D02*
X110343D01*
X109130Y37799D01*
X108201Y36870D01*
X107698Y35657D01*
Y34343D01*
X108201Y33130D01*
X109130Y32201D01*
X110343Y31698D01*
X111657D01*
X112870Y32201D01*
X113799Y33130D01*
X114302Y34343D01*
Y35657D01*
X113799Y36870D01*
X112870Y37799D01*
X111657Y38302D01*
D02*
G37*
G36*
X93657Y37302D02*
X92343D01*
X91130Y36799D01*
X90201Y35870D01*
X89698Y34657D01*
Y33343D01*
X90201Y32130D01*
X91130Y31201D01*
X92343Y30698D01*
X93657D01*
X94870Y31201D01*
X95799Y32130D01*
X96302Y33343D01*
Y34657D01*
X95799Y35870D01*
X94870Y36799D01*
X93657Y37302D01*
D02*
G37*
%LPD*%
D58*
X211156Y38620D02*
D03*
X126000Y100000D02*
D03*
X104000Y107000D02*
D03*
X209830Y407680D02*
D03*
Y397520D02*
D03*
Y387360D02*
D03*
Y377200D02*
D03*
Y367040D02*
D03*
Y356880D02*
D03*
Y346720D02*
D03*
Y336560D02*
D03*
Y326400D02*
D03*
X199670Y407680D02*
D03*
Y397520D02*
D03*
Y387360D02*
D03*
Y377200D02*
D03*
Y367040D02*
D03*
Y356880D02*
D03*
Y346720D02*
D03*
Y336560D02*
D03*
Y326400D02*
D03*
X189510Y387360D02*
D03*
Y367040D02*
D03*
Y356880D02*
D03*
Y346720D02*
D03*
Y336560D02*
D03*
Y326400D02*
D03*
X179350Y367040D02*
D03*
Y356880D02*
D03*
Y346720D02*
D03*
Y336560D02*
D03*
X169190Y407680D02*
D03*
X159030Y387360D02*
D03*
Y377200D02*
D03*
Y356880D02*
D03*
Y346720D02*
D03*
Y336560D02*
D03*
X148870Y387360D02*
D03*
Y346720D02*
D03*
X138710Y397520D02*
D03*
Y387360D02*
D03*
X128550D02*
D03*
X118390D02*
D03*
X98070D02*
D03*
X87910Y306080D02*
D03*
X77750Y407680D02*
D03*
Y387360D02*
D03*
Y356880D02*
D03*
X67590Y397520D02*
D03*
Y306080D02*
D03*
Y295920D02*
D03*
Y285760D02*
D03*
Y275600D02*
D03*
X190545Y43935D02*
D03*
X115000Y146000D02*
D03*
X106178Y147000D02*
D03*
X115000Y139000D02*
D03*
X168000Y131000D02*
D03*
X204000Y111000D02*
D03*
X166000Y112000D02*
D03*
X201000Y120000D02*
D03*
X167000D02*
D03*
X154373Y105997D02*
D03*
X210000Y181100D02*
D03*
Y192100D02*
D03*
X76611Y127172D02*
D03*
X52102Y139442D02*
D03*
X53051Y126729D02*
D03*
X41792Y117242D02*
D03*
X39452Y130651D02*
D03*
X12000Y65000D02*
D03*
Y74000D02*
D03*
X37758Y73000D02*
D03*
X37000Y64000D02*
D03*
X206000Y52000D02*
D03*
X197000D02*
D03*
X207000Y77000D02*
D03*
X198000D02*
D03*
X204000Y40054D02*
D03*
X191000Y37000D02*
D03*
X90162Y85574D02*
D03*
X80512Y67616D02*
D03*
X106948Y62472D02*
D03*
X93057Y101595D02*
D03*
X94793Y112219D02*
D03*
X65988Y100369D02*
D03*
X66000Y112000D02*
D03*
X145027Y145180D02*
D03*
X128214Y138000D02*
D03*
X181826Y161442D02*
D03*
X148849Y161221D02*
D03*
X138262Y162104D02*
D03*
X83228D02*
D03*
X83000Y146000D02*
D03*
X91831Y146884D02*
D03*
X37000Y194600D02*
D03*
X58000D02*
D03*
X79000D02*
D03*
X100000Y194000D02*
D03*
X121000Y194600D02*
D03*
X142000D02*
D03*
X163000D02*
D03*
X184000Y194600D02*
D03*
X37000Y215600D02*
D03*
X58000D02*
D03*
X79000D02*
D03*
X100000Y215000D02*
D03*
X121000Y215600D02*
D03*
X142000D02*
D03*
X163000D02*
D03*
X184000Y215600D02*
D03*
X37000Y236600D02*
D03*
X58000D02*
D03*
X79000D02*
D03*
X100000Y236000D02*
D03*
X121000Y236600D02*
D03*
X142000D02*
D03*
X163000D02*
D03*
X184000Y236600D02*
D03*
X37000Y257000D02*
D03*
X58000D02*
D03*
X79000D02*
D03*
X100000Y256400D02*
D03*
X121000Y257000D02*
D03*
X142000D02*
D03*
X163000D02*
D03*
X184000Y257000D02*
D03*
X37000Y278600D02*
D03*
X58000D02*
D03*
X79000D02*
D03*
X100000Y278000D02*
D03*
X121000Y278600D02*
D03*
X142000D02*
D03*
X163000D02*
D03*
X184000Y278600D02*
D03*
Y299600D02*
D03*
X163000Y299600D02*
D03*
X142000D02*
D03*
X121000D02*
D03*
X100000Y299000D02*
D03*
X79000Y299600D02*
D03*
X58000D02*
D03*
X37000D02*
D03*
X210000Y203100D02*
D03*
Y214100D02*
D03*
Y236100D02*
D03*
Y258100D02*
D03*
Y302100D02*
D03*
Y313100D02*
D03*
X149024Y334175D02*
D03*
X137823Y333314D02*
D03*
X126909Y334032D02*
D03*
X17430Y401507D02*
D03*
X68713Y403287D02*
D03*
X14291Y409878D02*
D03*
X11151Y401828D02*
D03*
X53974Y359649D02*
D03*
X23386Y401023D02*
D03*
X51000Y371000D02*
D03*
X50396Y377474D02*
D03*
X31414Y403184D02*
D03*
X11000Y339000D02*
D03*
X18519Y343994D02*
D03*
X26000Y349000D02*
D03*
X11000D02*
D03*
X49915Y341352D02*
D03*
X39824Y361855D02*
D03*
X63000Y38000D02*
D03*
X176000Y44000D02*
D03*
X111000Y35000D02*
D03*
X152000Y36000D02*
D03*
X137000D02*
D03*
X123000Y35000D02*
D03*
X93000Y34000D02*
D03*
X33000Y31000D02*
D03*
Y38000D02*
D03*
X32880Y45166D02*
D03*
X33000Y51645D02*
D03*
X15000Y50312D02*
D03*
X12791Y42000D02*
D03*
X6395Y41971D02*
D03*
X6826Y50312D02*
D03*
D59*
X110000Y420000D02*
D03*
M02*
